# SCM (Grand Teton) — schematic netlist excerpt (pin names and nets, part order shuffled) for the footprints in the layout excerpt that follows; sources: Cadence DE-HDL packaged netlist, KiCad conversion of 12092022_DA0F0TMDCD0_F0T_Management_Board_D_brd_V3_OCP.brd

C262  Q_CAP  0.1UF 25V 10% X7R  pkg 0402  page 52 : A = P12V_AUX ; B = GND
R100  Q_RES  33.2 1% CHIP  pkg 0402LF  page 46 : A = SPI_BMC_TPM_CS2_N_R ; B = SPI_BMC_TPM_CS2_R_N

(kicad_pcb
	(version 20260206)
	(generator "pcbnew")
	(generator_version "10.0")
	(general
		(thickness 1.6)
		(legacy_teardrops no)
	)
	(paper "A4")
	(title_block
		(title "12092022_DA0F0TMDCD0_F0T_Management_Board_D_brd_V3_OCP.brd")
		(comment 1 "Grand Teton / footprints 410-411 of 1440")
	)
	(layers
		(0 "F.Cu" signal "TOP")
		(4 "In1.Cu" signal "GND")
		(6 "In2.Cu" signal "IN1")
		(8 "In3.Cu" signal "GND1")
		(10 "In4.Cu" signal "IN2")
		(12 "In5.Cu" signal "VCC")
		(14 "In6.Cu" signal "VCC1")
		(16 "In7.Cu" signal "IN3")
		(18 "In8.Cu" signal "GND2")
		(20 "In9.Cu" signal "IN4")
		(22 "In10.Cu" signal "GND3")
		(2 "B.Cu" signal "BOTTOM")
		(9 "F.Adhes" user "F.Adhesive")
		(11 "B.Adhes" user "B.Adhesive")
		(13 "F.Paste" user "Package Geometry/Pastemask Top")
		(15 "B.Paste" user "Package Geometry/Pastemask Bottom")
		(5 "F.SilkS" user "Ref Des/Silkscreen Top")
		(7 "B.SilkS" user "Ref Des/Silkscreen Bottom")
		(1 "F.Mask" user "Board Geometry/Soldermask Top")
		(3 "B.Mask" user "Board Geometry/Soldermask Bottom")
		(17 "Dwgs.User" user "User.Drawings")
		(19 "Cmts.User" user "User.Comments")
		(21 "Eco1.User" user "User.Eco1")
		(23 "Eco2.User" user "User.Eco2")
		(25 "Edge.Cuts" user "Board Geometry/Outline")
		(27 "Margin" user)
		(31 "F.CrtYd" user "Package Geometry/Place Bound Top")
		(29 "B.CrtYd" user "Package Geometry/Place Bound Bottom")
		(35 "F.Fab" user "Ref Des/Assembly Top")
		(33 "B.Fab" user "Ref Des/Assembly Bottom")
	)
	(footprint ""
		(layer "F.Cu")
		(at 84.201 -97.917)
		(property "Reference" "R100"
			(at 0 0 0)
			(layer "F.SilkS")
			(hide yes)
			(effects
				(font
					(size 1.27 1.27)
				)
			)
		)
		(property "Value" ""
			(at 0 0 0)
			(layer "F.Fab")
			(effects
				(font
					(size 1.27 1.27)
				)
			)
		)
		(duplicate_pad_numbers_are_jumpers no)
		(fp_line
			(start -0.7874 -0.4064)
			(end 0.7874 -0.4064)
			(stroke
				(width 0.1524)
				(type default)
			)
			(layer "F.SilkS")
		)
		(fp_line
			(start -0.7874 0.4064)
			(end -0.7874 -0.4064)
			(stroke
				(width 0.1524)
				(type default)
			)
			(layer "F.SilkS")
		)
		(fp_line
			(start 0.7874 -0.4064)
			(end 0.7874 0.4064)
			(stroke
				(width 0.1524)
				(type default)
			)
			(layer "F.SilkS")
		)
		(fp_line
			(start 0.7874 0.4064)
			(end -0.7874 0.4064)
			(stroke
				(width 0.1524)
				(type default)
			)
			(layer "F.SilkS")
		)
		(fp_line
			(start -0.67945 -0.305054)
			(end -0.12065 -0.305054)
			(stroke
				(width 0.1)
				(type default)
			)
			(layer "F.Fab")
		)
		(fp_line
			(start -0.67945 0.3048)
			(end -0.67945 -0.305054)
			(stroke
				(width 0.1)
				(type default)
			)
			(layer "F.Fab")
		)
		(fp_line
			(start -0.12065 -0.305054)
			(end -0.12065 -0.2794)
			(stroke
				(width 0.1)
				(type default)
			)
			(layer "F.Fab")
		)
		(fp_line
			(start -0.12065 -0.2794)
			(end 0.12065 -0.2794)
			(stroke
				(width 0.1)
				(type default)
			)
			(layer "F.Fab")
		)
		(fp_line
			(start -0.12065 0.2794)
			(end -0.12065 0.3048)
			(stroke
				(width 0.1)
				(type default)
			)
			(layer "F.Fab")
		)
		(fp_line
			(start -0.12065 0.3048)
			(end -0.67945 0.3048)
			(stroke
				(width 0.1)
				(type default)
			)
			(layer "F.Fab")
		)
		(fp_line
			(start 0.120396 0.2794)
			(end -0.12065 0.2794)
			(stroke
				(width 0.1)
				(type default)
			)
			(layer "F.Fab")
		)
		(fp_line
			(start 0.120396 0.3048)
			(end 0.120396 0.2794)
			(stroke
				(width 0.1)
				(type default)
			)
			(layer "F.Fab")
		)
		(fp_line
			(start 0.12065 -0.3048)
			(end 0.67945 -0.3048)
			(stroke
				(width 0.1)
				(type default)
			)
			(layer "F.Fab")
		)
		(fp_line
			(start 0.12065 -0.2794)
			(end 0.12065 -0.3048)
			(stroke
				(width 0.1)
				(type default)
			)
			(layer "F.Fab")
		)
		(fp_line
			(start 0.67945 -0.3048)
			(end 0.67945 0.3048)
			(stroke
				(width 0.1)
				(type default)
			)
			(layer "F.Fab")
		)
		(fp_line
			(start 0.67945 0.3048)
			(end 0.120396 0.3048)
			(stroke
				(width 0.1)
				(type default)
			)
			(layer "F.Fab")
		)
		(pad "1" smd circle
			(at -0.40005 0)
			(size 0 0)
			(layers "F.Cu" "F.Mask" "F.Paste")
			(net "SPI_BMC_TPM_CS2_N_R")
		)
		(pad "2" smd circle
			(at 0.40005 0)
			(size 0 0)
			(layers "F.Cu" "F.Mask" "F.Paste")
			(net "SPI_BMC_TPM_CS2_R_N")
		)
	)
	(footprint ""
		(layer "F.Cu")
		(at 10.287 -59.055 90)
		(property "Reference" "C262"
			(at 0 0 90)
			(layer "F.SilkS")
			(hide yes)
			(effects
				(font
					(size 1.27 1.27)
				)
			)
		)
		(property "Value" ""
			(at 0 0 90)
			(layer "F.Fab")
			(effects
				(font
					(size 1.27 1.27)
				)
			)
		)
		(duplicate_pad_numbers_are_jumpers no)
		(fp_line
			(start 0.7874 -0.4064)
			(end 0.7874 0.4064)
			(stroke
				(width 0.1524)
				(type default)
			)
			(layer "F.SilkS")
		)
		(fp_line
			(start -0.7874 -0.4064)
			(end 0.7874 -0.4064)
			(stroke
				(width 0.1524)
				(type default)
			)
			(layer "F.SilkS")
		)
		(fp_line
			(start 0.7874 0.4064)
			(end -0.7874 0.4064)
			(stroke
				(width 0.1524)
				(type default)
			)
			(layer "F.SilkS")
		)
		(fp_line
			(start -0.7874 0.4064)
			(end -0.7874 -0.4064)
			(stroke
				(width 0.1524)
				(type default)
			)
			(layer "F.SilkS")
		)
		(fp_line
			(start -0.12065 -0.305054)
			(end -0.12065 -0.2794)
			(stroke
				(width 0.1)
				(type default)
			)
			(layer "F.Fab")
		)
		(fp_line
			(start -0.67945 -0.305054)
			(end -0.12065 -0.305054)
			(stroke
				(width 0.1)
				(type default)
			)
			(layer "F.Fab")
		)
		(fp_line
			(start 0.67945 -0.3048)
			(end 0.67945 0.3048)
			(stroke
				(width 0.1)
				(type default)
			)
			(layer "F.Fab")
		)
		(fp_line
			(start 0.12065 -0.3048)
			(end 0.67945 -0.3048)
			(stroke
				(width 0.1)
				(type default)
			)
			(layer "F.Fab")
		)
		(fp_line
			(start 0.12065 -0.2794)
			(end 0.12065 -0.3048)
			(stroke
				(width 0.1)
				(type default)
			)
			(layer "F.Fab")
		)
		(fp_line
			(start -0.12065 -0.2794)
			(end 0.12065 -0.2794)
			(stroke
				(width 0.1)
				(type default)
			)
			(layer "F.Fab")
		)
		(fp_line
			(start 0.120396 0.2794)
			(end -0.12065 0.2794)
			(stroke
				(width 0.1)
				(type default)
			)
			(layer "F.Fab")
		)
		(fp_line
			(start -0.12065 0.2794)
			(end -0.12065 0.3048)
			(stroke
				(width 0.1)
				(type default)
			)
			(layer "F.Fab")
		)
		(fp_line
			(start 0.67945 0.3048)
			(end 0.120396 0.3048)
			(stroke
				(width 0.1)
				(type default)
			)
			(layer "F.Fab")
		)
		(fp_line
			(start 0.120396 0.3048)
			(end 0.120396 0.2794)
			(stroke
				(width 0.1)
				(type default)
			)
			(layer "F.Fab")
		)
		(fp_line
			(start -0.12065 0.3048)
			(end -0.67945 0.3048)
			(stroke
				(width 0.1)
				(type default)
			)
			(layer "F.Fab")
		)
		(fp_line
			(start -0.67945 0.3048)
			(end -0.67945 -0.305054)
			(stroke
				(width 0.1)
				(type default)
			)
			(layer "F.Fab")
		)
		(pad "1" smd circle
			(at -0.40005 0 90)
			(size 0 0)
			(layers "F.Cu" "F.Mask" "F.Paste")
			(net "P12V_AUX")
		)
		(pad "2" smd circle
			(at 0.40005 0 90)
			(size 0 0)
			(layers "F.Cu" "F.Mask" "F.Paste")
			(net "GND")
		)
	)
)
